# S9S_MB_2U (Grand Teton) — schematic parts with pin connectivity, parts 2374–2533 of 6093; source: Cadence DE-HDL packaged netlist (pstxprt.dat, pstxnet.dat, pstchip.dat)

PC2146  Q_CAP  1UF 25V 10% EMPTY  pkg C0402  page 162 : 1 = GND ; 2 = P12V_OCP_REG_2
PC2147  Q_CAP  1UF 25V 10% X6S  pkg C0402  page 162 : 1 = GND ; 2 = P3V3_OCP_REG_2
PC2149  Q_CAP  0.01UF 50V 10% EMPTY  pkg C0402  page 162 : 1 = P3V3_OCP_V3_2_R ; 2 = P3V3_OCP_GATE_2
PC2150  Q_CAP  3900PF 50V 10% EMPTY  pkg C0402  page 162 : 1 = P12V_OCP_GATE_2 ; 2 = GND
PC2151  Q_CAP  6800PF 50V 10% X7R  pkg C0402  page 162 : 1 = P3V3_OCP_GATE_2 ; 2 = GND
PC2152  Q_CAP  0.1UF 25V 10% X7R  pkg 0402  page 162 : 1 = P12V_OCP_V3_2 ; 2 = GND
PC2153  Q_CAP  0.22UF 16V 10% X7R  pkg 0402  page 157 : 1 = P12V_OCP_TIMER_1 ; 2 = GND
PC2154  Q_CAP  1UF 25V 10% X6S  pkg C0402  page 157 : 1 = P12V_AUX ; 2 = GND
PC2155  Q_CAP  0.047UF 25V 10% X7R  pkg C0402  page 157 : 1 = P12V_OCP_SS_1 ; 2 = GND
PC2156  Q_CAP  100NF 50V 10% X7R  pkg C0402  page 157 : 1 = P12V_OCP_IMON_1 ; 2 = GND
PC2157  Q_CAP  39PF 50V 5% EMPTY  pkg C0402  page 157 : 1 = P3V3_OCP_MODE_1 ; 2 = GND
PC2158  Q_CAP  2.2UF 16V 20% X7R  pkg C0603  page 157 : 1 = P12V_OCP_AVIN_PD_1 ; 2 = GND
PC2159  Q_CAP  1UF 25V 10% EMPTY  pkg C0402  page 157 : 1 = P3V3_AUX ; 2 = GND
PC2160  Q_CAP  0.1UF 25V 10% X7R  pkg 0402  page 157 : 1 = P12V_OCP_SFF ; 2 = GND
PC2161  Q_CAP  0.068UF 16V 10% EMPTY  pkg 0402  page 157 : 1 = P3V3_OCP_DVDT_1 ; 2 = GND
PC2162  Q_CAP  100PF 50V 5% EMPTY  pkg 0402  page 157 : 1 = P3V3_OCP_GATE_1 ; 2 = GND
PC2163  Q_CAP  10UF 16V 10% EMPTY  pkg C0805  page 157 : 1 = P3V3_OCP_SFF_R ; 2 = GND
PC2164  Q_CAP  0.22UF 16V 10% X7R  pkg 0402  page 163 : 1 = P12V_OCP_TIMER_2 ; 2 = GND
PC2165  Q_CAP  1UF 25V 10% X6S  pkg C0402  page 163 : 1 = P12V_AUX ; 2 = GND
PC2166  Q_CAP  0.047UF 25V 10% X7R  pkg C0402  page 163 : 1 = P12V_OCP_SS_2 ; 2 = GND
PC2167  Q_CAP  100PF 50V 5% X7R  pkg 0402  page 163 : 1 = P12V_OCP_IMON_2 ; 2 = GND
PC2168  Q_CAP  39PF 50V 5% EMPTY  pkg C0402  page 163 : 1 = P3V3_OCP_MODE_2 ; 2 = GND
PC2169  Q_CAP  1UF 25V 10% EMPTY  pkg C0402  page 163 : 1 = P3V3_AUX ; 2 = GND
PC2170  Q_CAPP  330UF 2.5V +10/-35% SPCAP  pkg SMLF  page 272 : 1 = PVCCFA_EHV_FIVRA_CPU0 ; 2 = GND
PC2171  Q_CAPP  330UF 2.5V +10/-35% SPCAP  pkg SMLF  page 290 : 1 = PVCCFA_EHV_FIVRA_CPU1 ; 2 = GND
PC2172  Q_CAPP  330UF 2.5V +10/-35% SPCAP  pkg SMLF  page 289 : 1 = PVCCFA_EHV_FIVRA_CPU1 ; 2 = GND
PC2173  Q_CAP  10UF 16V 10% EMPTY  pkg C0805  page 163 : 1 = P3V3_OCP_V3_2_R ; 2 = GND
PC2174  Q_CAP  0.1UF 25V 10% X7R  pkg 0402  page 163 : 1 = P12V_OCP_V3_2 ; 2 = GND
PC2180  Q_CAPP  560UF 2.5V 20% OSCON  pkg THLF  page 276 : 1 = PVCCFA_EHV_CPU0 ; 2 = GND
PC2181  Q_CAP  1UF 25V 10% X6S  pkg C0402  page 302 : 1 = HSC_VDD_R_2 ; 2 = AGND_HSC
PC2182  Q_CAP  220PF 50V 10% X7R  pkg 0402  page 302 : 1 = HSC_ON ; 2 = AGND_HSC
PC2183  Q_CAP  220PF 50V 10% EMPTY  pkg 0402  page 302 : 1 = HSC_ON ; 2 = AGND_HSC
PC2184  Q_CAP  0.068UF 16V 10% X7R  pkg 0402  page 302 : 1 = HSC_SS ; 2 = AGND_HSC
PC2185  Q_CAP  0.068UF 16V 10% X7R  pkg 0402  page 302 : 1 = HSC_SS ; 2 = AGND_HSC
PC2186  Q_CAP  1UF 25V 10% X6S  pkg C0402  page 301 : 1 = HSC_VDD_R ; 2 = AGND_HSC
PC2187  Q_CAP  1UF 25V 10% X6S  pkg C0402  page 301 : 1 = HSC_VDD_R ; 2 = AGND_HSC
PC2188  Q_CAP  1UF 25V 10% X6S  pkg C0402  page 301 : 1 = P12V_PSU ; 2 = GND
PC2189  Q_CAP  0.01UF 50V 10% X7R  pkg C0402  page 301 : 1 = HSC_VSENSE ; 2 = AGND_HSC
PC2190  Q_CAP  0.01UF 50V 10% X7R  pkg C0402  page 301 : 1 = HSC_VOSEN ; 2 = AGND_HSC
PC2191  Q_CAP  0.068UF 16V 10% X7R  pkg 0402  page 301 : 1 = HSC_SS ; 2 = AGND_HSC
PC2192  Q_CAP  0.001UF 50V 10% X7R  pkg C0402  page 301 : 1 = HSC_VTEMP ; 2 = AGND_HSC
PC2193  Q_CAP  0.047UF 25V 10% X7R  pkg C0402  page 301 : 1 = HSC_IMON ; 2 = AGND_HSC
PC2196  Q_CAP  0.22UF 16V 10% X7R  pkg 0402  page 193 : 1 = P12V_E1S_TIMER_0 ; 2 = GND
PC2197  Q_CAP  39PF 50V 5% EMPTY  pkg C0402  page 193 : 1 = P3V3_E1S_MODE_0 ; 2 = GND
PC2198  Q_CAP  1UF 25V 10% X6S  pkg C0402  page 193 : 1 = P12V_AUX ; 2 = GND
PC2199  Q_CAPP  560UF 2.5V 20% OSCON  pkg THLF  page 294 : 1 = PVCCFA_EHV_CPU1 ; 2 = GND
PC2200  Q_CAP  1UF 25V 10% EMPTY  pkg C0402  page 193 : 1 = P3V3_AUX ; 2 = GND
PC2201  Q_CAP  0.068UF 16V 10% EMPTY  pkg 0402  page 193 : 1 = P3V3_E1S_DVDT_0 ; 2 = GND
PC2202  Q_CAP  100NF 50V 10% X7R  pkg C0402  page 193 : 1 = P12V_E1S_IMON_0 ; 2 = GND
PC2203  Q_CAP  100PF 50V 5% EMPTY  pkg 0402  page 193 : 1 = P3V3_E1S_GATE_0_PU293 ; 2 = GND
PC2204  Q_CAP  10UF 16V 10% EMPTY  pkg C0805  page 193 : 1 = P3V3_E1S_0_R ; 2 = GND
PC2205  Q_CAP  2.2UF 16V 20% X7R  pkg C0603  page 193 : 1 = P12V_E1S_AVIN_PD_0 ; 2 = GND
PC2206  Q_CAP  0.1UF 25V 10% X7R  pkg 0402  page 193 : 1 = P12V_E1S_0 ; 2 = GND
PC2207  Q_CAP  1UF 25V 10% X6S  pkg C0402  page 192 : 1 = P12V_AUX ; 2 = GND
PC2208  Q_CAP  1UF 25V 10% X6S  pkg C0402  page 192 : 1 = P3V3_AUX ; 2 = GND
PC2209  Q_CAP  1UF 25V 10% EMPTY  pkg C0402  page 192 : 1 = P12V_E1S_VCC_0 ; 2 = GND
PC2210  Q_CAP  1UF 25V 10% X6S  pkg C0402  page 192 : 1 = P3V3_E1S_VCC_0 ; 2 = GND
PC2211  Q_CAP  1UF 25V 10% EMPTY  pkg C0402  page 192 : 1 = GND ; 2 = P12V_E1S_REG_0
PC2212  Q_CAP  1UF 25V 10% X6S  pkg C0402  page 192 : 1 = GND ; 2 = P3V3_E1S_REG_0
PC2213  Q_CAP  0.01UF 50V 10% EMPTY  pkg C0402  page 192 : 1 = P3V3_E1S_0_R ; 2 = P3V3_E1S_GATE_0
PC2214  Q_CAP  0.01UF 50V 10% EMPTY  pkg C0402  page 192 : 1 = P12V_E1S_0 ; 2 = P12V_E1S_GATE_0
PC2215  Q_CAP  3900PF 50V 10% EMPTY  pkg C0402  page 192 : 1 = P12V_E1S_GATE_0 ; 2 = GND
PC2216  Q_CAP  6800PF 50V 10% X7R  pkg C0402  page 192 : 1 = P3V3_E1S_GATE_0 ; 2 = GND
PC2217  Q_CAP  0.1UF 25V 10% X7R  pkg 0402  page 192 : 1 = P12V_E1S_0 ; 2 = GND
PC2218  Q_CAP  0.1UF 25V 10% X7R  pkg 0402  page 192 : 1 = P3V3_E1S_0_R ; 2 = GND
PC2219  Q_CAP  10UF 16V 10% X6S  pkg C0805  page 192 : 1 = P12V_E1S_0 ; 2 = GND
PC2220  Q_CAP  10UF 16V 10% X6S  pkg C0805  page 192 : 1 = P3V3_E1S_0_R ; 2 = GND
PC2221  Q_CAP  1UF 25V 10% X6S  pkg C0402  page 282 : 1 = PVNN_MAIN_CPU0_VCC ; 2 = GND
PC2222  Q_CAP  1UF 25V 10% X6S  pkg C0402  page 300 : 1 = PVNN_MAIN_CPU1_VCC ; 2 = GND
PC2223  Q_CAP  1UF 25V 10% X6S  pkg C0402  page 303 : 1 = HSC_VDD_R_4 ; 2 = AGND_HSC
PC2224  Q_CAP  220PF 50V 10% EMPTY  pkg 0402  page 303 : 1 = HSC_ON ; 2 = AGND_HSC
PC2225  Q_CAP  220PF 50V 10% EMPTY  pkg 0402  page 303 : 1 = HSC_ON ; 2 = AGND_HSC
PC2226  Q_CAP  0.068UF 16V 10% X7R  pkg 0402  page 303 : 1 = HSC_SS ; 2 = AGND_HSC
PC2227  Q_CAP  0.068UF 16V 10% X7R  pkg 0402  page 303 : 1 = HSC_SS ; 2 = AGND_HSC
PC2229  Q_CAP  0.22UF 16V 10% X7R  pkg 0402  page 242 : 1 = P12V_SCM_TIMER ; 2 = GND
PC2230  Q_CAP  1UF 25V 10% X6S  pkg C0402  page 242 : 1 = P12V_AUX ; 2 = GND
PC2231  Q_CAP  1UF 25V 10% X6S  pkg C0402  page 242 : 1 = P12V_AUX ; 2 = GND
PC2232  Q_CAP  0.047UF 25V 10% X7R  pkg C0402  page 242 : 1 = P12V_SCM_SS ; 2 = GND
PC2233  Q_CAP  1UF 25V 10% EMPTY  pkg C0402  page 242 : 1 = P12V_SCM_VCC ; 2 = GND
PC2234  Q_CAP  1UF 25V 10% EMPTY  pkg C0402  page 242 : 1 = GND ; 2 = P12V_SCM_REG
PC2235  Q_CAP  100NF 50V 10% X7R  pkg C0402  page 242 : 1 = P12V_SCM_IMON ; 2 = GND
PC2236  Q_CAP  0.01UF 50V 10% EMPTY  pkg C0402  page 242 : 1 = P12V_SCM_R ; 2 = P12V_SCM_GATE
PC2237  Q_CAP  3900PF 50V 10% EMPTY  pkg C0402  page 242 : 1 = P12V_SCM_GATE ; 2 = GND
PC2238  Q_CAP  0.1UF 25V 10% X7R  pkg 0402  page 242 : 1 = P12V_SCM_R ; 2 = GND
PC2239  Q_CAP  2.2UF 16V 20% X7R  pkg C0603  page 242 : 1 = P12V_SCM_AVIN_PD ; 2 = GND
PC2240  Q_CAP  10UF 16V 10% X6S  pkg C0805  page 242 : 1 = P12V_SCM_R ; 2 = GND
PC2241  Q_CAP  0.1UF 25V 10% X7R  pkg 0402  page 242 : 1 = P12V_SCM_R ; 2 = GND
PC2242  Q_CAP  22UF 16V 20% X6S  pkg C0805  page 242 : 1 = P12V_SCM_R ; 2 = GND
PC2260  Q_CAP  22UF 16V 20% X6S  pkg C0805  page 259 : 1 = SW_P3V3_AUX_FLT ; 2 = GND
PC2261  Q_CAP  22UF 16V 20% X6S  pkg C0805  page 259 : 1 = SW_P3V3_AUX_FLT ; 2 = GND
PC2262  Q_CAP  22UF 16V 20% X6S  pkg C0805  page 259 : 1 = SW_P3V3_AUX_FLT ; 2 = GND
PC2263  Q_CAP  22UF 16V 20% X6S  pkg C0805  page 259 : 1 = SW_P3V3_AUX_FLT ; 2 = GND
PC2277  Q_CAP  0.01UF 25V 10% X7R  pkg 0402  page 300 : 1 = PVNN_MAIN_CPU1_FB_RC ; 2 = GND
PC2279  Q_CAP  0.01UF 25V 10% X7R  pkg 0402  page 262 : 1 = SH_P1V05_PCH_AUX_P ; 2 = SH_P1V05_PCH_AUX_N
PC2280  Q_CAP  10UF 16V 10% X6S  pkg C0805  page 192 : 1 = P12V_E1S_0 ; 2 = GND
PC2281  Q_CAP  0.047UF 25V 10% X7R  pkg C0402  page 193 : 1 = P12V_E1S_SS_0 ; 2 = GND
PC2282  Q_CAP  0.01UF 25V 10% X7R  pkg 0402  page 299 : 1 = SH_PVPP_HBM_CPU1_P ; 2 = SH_PVPP_HBM_CPU1_N
PC2286  Q_CAP  1000PF 50V 5% EMPTY  pkg 0402  page 262 : 1 = FM_P1V05_PCH_AUX_R_EN ; 2 = GND
PC2336  Q_CAPP  330UF 2.5V +10/-35% EMPTY  pkg SMLF  page 267 : 1 = PVCCIN_CPU0 ; 2 = GND
PC2340  Q_CAP  560PF 50V 10% X7R  pkg C0402  page 242 : 1 = P12V_SCM_ISET_R ; 2 = GND
PC2341  Q_CAP  560PF 50V 10% X7R  pkg C0402  page 193 : 1 = P12V_E1S_ISET_0_R ; 2 = GND
PC2342  Q_CAP  22UF 16V 20% X6S  pkg C0805  page 259 : 1 = SW_P3V3_AUX_FLT ; 2 = GND
PC2343  Q_CAP  22UF 16V 20% X6S  pkg C0805  page 259 : 1 = SW_P3V3_AUX_FLT ; 2 = GND
PC2344  Q_CAP  22UF 16V 20% X6S  pkg C0805  page 259 : 1 = SW_P3V3_AUX_FLT ; 2 = GND
PC2345  Q_CAPP  270UF 16V 20% OSCON  pkg THLF  page 267 : 1 = SW_P12V_PVCCIN_CPU0_FLT ; 2 = GND
PC2346  Q_CAPP  270UF 16V 20% OSCON  pkg THLF  page 285 : 1 = SW_P12V_PVCCIN_CPU1_FLT ; 2 = GND
PC2347  Q_CAP  1NF 50V 10% EMPTY  pkg 0402  page 302 : 1 = HSC_OCREF ; 2 = AGND_HSC
PC2348  Q_CAP  1NF 50V 10% EMPTY  pkg 0402  page 302 : 1 = HSC_OCREF ; 2 = AGND_HSC
PC2349  Q_CAP  1NF 50V 10% EMPTY  pkg 0402  page 303 : 1 = HSC_OCREF ; 2 = AGND_HSC
PC2350  Q_CAP  1NF 50V 10% EMPTY  pkg 0402  page 303 : 1 = HSC_OCREF ; 2 = AGND_HSC
PC2361  Q_CAP  0.1UF 25V 10% EMPTY  pkg 0402  page 266 : 1 = PVCCIN_CPU0_VCC ; 2 = GND
PC2362  Q_CAP  0.1UF 25V 10% EMPTY  pkg 0402  page 274 : 1 = PVCCINFAON_CPU0_VCC ; 2 = GND
PC2365  Q_CAP  0.1UF 25V 10% EMPTY  pkg 0402  page 278 : 1 = PVCCD_HV_CPU0_VCC ; 2 = GND
PC2366  Q_CAP  0.1UF 25V 10% EMPTY  pkg 0402  page 284 : 1 = PVCCIN_CPU1_VCC ; 2 = GND
PC2367  Q_CAP  0.1UF 25V 10% EMPTY  pkg 0402  page 292 : 1 = PVCCINFAON_CPU1_VCC ; 2 = GND
PC2368  Q_CAP  0.1UF 25V 10% EMPTY  pkg 0402  page 296 : 1 = PVCCD_HV_CPU1_VCC ; 2 = GND
PC2643  Q_CAP  1UF 25V 10% X6S  pkg C0402  page 281 : 1 = PVPP_HBM_CPU0_VCC ; 2 = GND
PC2645  Q_CAPP  330UF 2.5V +10/-35% SPCAP  pkg SMLF  page 271 : 1 = PVCCFA_EHV_FIVRA_CPU0 ; 2 = GND
PC2946  Q_CAP  2.2UF 10V 10% X6S  pkg C0402  page 275 : 1 = PVCCFA_EHV_CPU0_PVCC ; 2 = GND
PC2947  Q_CAP  2.2UF 10V 10% X6S  pkg C0402  page 275 : 1 = PVCCFA_EHV_CPU0_PVCC ; 2 = GND
PC2948  Q_CAP  2.2UF 10V 10% X6S  pkg C0402  page 279 : 1 = PVCCFA_EHV_CPU0_PVCC ; 2 = GND
PC2949  Q_CAP  2.2UF 10V 10% X6S  pkg C0402  page 293 : 1 = PVCCFA_EHV_CPU1_PVCC ; 2 = GND
PC2950  Q_CAP  2.2UF 10V 10% X6S  pkg C0402  page 293 : 1 = PVCCFA_EHV_CPU1_PVCC ; 2 = GND
PC2951  Q_CAP  2.2UF 10V 10% X6S  pkg C0402  page 297 : 1 = PVCCFA_EHV_CPU1_PVCC ; 2 = GND
PC3272  Q_CAP  1UF 25V 10% X6S  pkg C0402  page 303 : 1 = HSC_VDD_R_3 ; 2 = AGND_HSC
PC4056  Q_CAP  3900PF 50V 10% EMPTY  pkg C0402  page 156 : 1 = P12V_OCP_GATE_1 ; 2 = GND
PC5328  Q_CAP  1UF 25V 10% X6S  pkg C0402  page 156 : 1 = P3V3_AUX ; 2 = GND
PD15  ZENER_AC  5.0SMDJ14A IC  pkg D2723_SMCXC  page 304 : A = GND ; C = P12V_PSU_FUSE
PD16  ZENER_AC  5.0SMDJ14A IC  pkg D2723_SMCXC  page 304 : A = GND ; C = P12V_PSU_FUSE

PD17  SS15P3SM386A  SS15P3S-M3/86A IC  pkg TO277A_4-3X6-1  page 304
  1  ANODE_1  IN  = GND
  2  ANODE_2  IN  = GND
  K  CATHODE  OUT  = P12V_AUX

PD101  DIODE_TVS  SMF14A IC  pkg SOD123F  page 156 : A = GND ; C = P12V_AUX
PD102  SCHOTTKY_AC  B340A-13-F IC  pkg D2010XF  page 156 : A = GND ; C = P12V_OCP_SFF
PD103  SCHOTTKY_AC  B340A-13-F IC  pkg D2010XF  page 156 : A = GND ; C = P3V3_OCP_SFF_R
PD107  DIODE_TVS  SMF14A IC  pkg SOD123F  page 162 : A = GND ; C = P12V_AUX
PD108  SCHOTTKY_AC  B340A-13-F IC  pkg D2010XF  page 162 : A = GND ; C = P12V_OCP_V3_2
PD109  SCHOTTKY_AC  B340A-13-F IC  pkg D2010XF  page 162 : A = GND ; C = P3V3_OCP_V3_2_R
PD112  SCHOTTKY_AC  B340A-13-F IC  pkg D2010XF  page 192 : A = GND ; C = P12V_E1S_0
PD113  SCHOTTKY_AC  B340A-13-F IC  pkg D2010XF  page 192 : A = GND ; C = P3V3_E1S_0_R
PD114  DIODE_TVS  SMF14A IC  pkg SOD123F  page 192 : A = GND ; C = P12V_AUX
PD115  DIODE_TVS  SMF14A IC  pkg SOD123F  page 242 : A = GND ; C = P12V_AUX
PD116  SCHOTTKY_AC  B340A-13-F IC  pkg D2010XF  page 242 : A = GND ; C = P12V_SCM_R

PJ42  SCONN21_9193031121LF  SCONN21_91930-31121LF EMPTY  pkg CON_F21S2H2D2S_P1W4-22_LDH  page 305
  1  \1\  BI  = P12V_PSU
  2  \2\  BI  = P12V_HSC_SENSE1_P
  3  \3\  BI  = P12V_HSC_SENSE1_N
  4  \4\  BI  = P12V_HSC_SENSE2_P
  5  \5\  BI  = P12V_HSC_SENSE2_N
  6  \6\  BI  = P12V_HSC_ADC_N
  7  \7\  BI  = P12V_HSC_ADC_P
  8  \8\  BI  = P12V_HSC_GATE1
  9  \9\  BI  = P12V_HSC_GATE2
  10  \10\  BI  = P12V_AUX
  11  \11\  BI  = GND
  12  \12\  BI  = P3V3_AUX
  13  \13\  BI  = IRQ_HSC_FAULT_N
  14  \14\  BI  = HSC_EN
  15  \15\  BI  = MB0_P12V_STBY_PWRGD
  16  \16\  BI  = HSC_CSOUT
  17  \17\  BI  = HSC_TYPE_ADC
  18  \18\  BI  = SMB_SML1_PMBUS_HSC_MODULE_SCL
  19  \19\  BI  = SMB_SML1_PMBUS_HSC_MODULE_SDA
  20  \20\  BI  = IRQ_SML1_PMBUS_ALERT_N
  21  \21\  BI  = GND
  G1  G1  POWER  = GND
  G2  G2  POWER  = GND

PJ45  Q_SHORT  EMPTY  pkg SM  page 274 : 1 = VSENSE_PVCCINFAON_CPU0_DP ; 2 = SH_PVCCINFAON_CPU0
PJ46  Q_SHORT  EMPTY  pkg SM  page 274 : 1 = VSENSE_PVCCFA_EHV_CPU0_DP ; 2 = SH_PVCCFA_EHV_CPU0
PJ47  Q_SHORT  EMPTY  pkg SM  page 266 : 1 = VSENSE_PVCCIN_CPU0_DP ; 2 = SH_PVCCIN_CPU0
PJ48  Q_SHORT  EMPTY  pkg SM  page 296 : 1 = VSENSE_PVCCD_HV_CPU1_DP ; 2 = SH_PVCCD_HV_CPU1
PJ49  Q_SHORT  EMPTY  pkg SM  page 284 : 1 = VSENSE_PVCCFA_EHV_FIVRA_CPU1_DP ; 2 = SH_PVCCFA_EHV_FIVRA_CPU1
PJ50  Q_SHORT  EMPTY  pkg SM  page 292 : 1 = VSENSE_PVCCINFAON_CPU1_DP ; 2 = SH_PVCCINFAON_CPU1
PJ51  Q_SHORT  EMPTY  pkg SM  page 292 : 1 = VSENSE_PVCCFA_EHV_CPU1_DP ; 2 = SH_PVCCFA_EHV_CPU1
PJ52  Q_SHORT  EMPTY  pkg SM  page 284 : 1 = VSENSE_PVCCIN_CPU1_DP ; 2 = SH_PVCCIN_CPU1
PJ53  Q_SHORT  EMPTY  pkg SM  page 266 : 1 = VSENSE_PVCCFA_EHV_FIVRA_CPU0_DP ; 2 = SH_PVCCFA_EHV_FIVRA_CPU0
PJ54  Q_SHORT  EMPTY  pkg SM  page 278 : 1 = VSENSE_PVCCD_HV_CPU0_DP ; 2 = SH_PVCCD_HV_CPU0
PJ62  Q_SHORT  EMPTY  pkg SM  page 262 : 1 = SH_P1V05_PCH_AUX_P ; 2 = P1V05_PCH_AUX
PJ63  Q_SHORT  EMPTY  pkg SM  page 262 : 1 = SH_P1V05_PCH_AUX_N ; 2 = GND
PJ64  Q_SHORT  EMPTY  pkg SM  page 281 : 1 = SH_PVPP_HBM_CPU0_P ; 2 = PVPP_HBM_CPU0
PJ65  Q_SHORT  EMPTY  pkg SM  page 281 : 1 = SH_PVPP_HBM_CPU0_N ; 2 = GND
PJ66  Q_SHORT  EMPTY  pkg SM  page 299 : 1 = SH_PVPP_HBM_CPU1_P ; 2 = PVPP_HBM_CPU1
PJ67  Q_SHORT  EMPTY  pkg SM  page 299 : 1 = SH_PVPP_HBM_CPU1_N ; 2 = GND

PJP1  CONN3_210HP1030BR1  CONN3_210-HP1-030BR1 IO  pkg HEADER1X3XG  page 266
  1  \1\  BI  = SMB_VR_3V3AUX_SCL_R3
  2  \2\  BI  = GND
  3  \3\  BI  = SMB_VR_3V3AUX_SDA_R3

PL2  Q_INDUCTOR  130NH/106A IND  pkg SMLF  page 272 : 1 = SW_PVCCFA_EHV_FIVRA_CPU0_SW3 ; 2 = PVCCFA_EHV_FIVRA_CPU0
